(kicad_pcb
	(version 20260206)
	(generator "pcbnew")
	(generator_version "10.0")
	(general
		(thickness 1.6)
		(legacy_teardrops no)
	)
	(paper "A4")
	(title_block
		(title "Wiwynn_Tioga_Pass_MB.brd")
		(comment 1 "Tioga Pass / footprint 2445 of 4770 (J9M1), pads 124-243 of 291")
	)
	(layers
		(0 "F.Cu" signal "TOP")
		(4 "In1.Cu" signal "L2GND")
		(6 "In2.Cu" signal "L3")
		(8 "In3.Cu" signal "L4GND")
		(10 "In4.Cu" signal "L5")
		(12 "In5.Cu" signal "L6GND")
		(14 "In6.Cu" signal "L7VCC")
		(16 "In7.Cu" signal "L8VCC")
		(18 "In8.Cu" signal "L9GND")
		(20 "In9.Cu" signal "L10")
		(22 "In10.Cu" signal "L11GND")
		(24 "In11.Cu" signal "L12")
		(26 "In12.Cu" signal "L13GND")
		(2 "B.Cu" signal "BOTTOM")
		(9 "F.Adhes" user "F.Adhesive")
		(11 "B.Adhes" user "B.Adhesive")
		(13 "F.Paste" user "Package Geometry/Pastemask Top")
		(15 "B.Paste" user "Package Geometry/Pastemask Bottom")
		(5 "F.SilkS" user "Ref Des/Silkscreen Top")
		(7 "B.SilkS" user "Ref Des/Silkscreen Bottom")
		(1 "F.Mask" user "Board Geometry/Soldermask Top")
		(3 "B.Mask" user "Board Geometry/Soldermask Bottom")
		(17 "Dwgs.User" user "User.Drawings")
		(19 "Cmts.User" user "User.Comments")
		(21 "Eco1.User" user "User.Eco1")
		(23 "Eco2.User" user "User.Eco2")
		(25 "Edge.Cuts" user "Board Geometry/Outline")
		(27 "Margin" user)
		(31 "F.CrtYd" user "Package Geometry/Place Bound Top")
		(29 "B.CrtYd" user "Package Geometry/Place Bound Bottom")
		(35 "F.Fab" user "Ref Des/Assembly Top")
		(33 "B.Fab" user "Ref Des/Assembly Bottom")
	)
	(footprint ""
		(layer "B.Cu")
		(at 29.699458 -132.876036 90)
		(property "Reference" "J9M1"
			(at 2.352548 37.991542 0)
			(unlocked yes)
			(layer "B.SilkS")
			(effects
				(font
					(size 0.7874 0.5842)
					(thickness 0.1524)
				)
				(justify left mirror)
			)
		)
		(property "Value" ""
			(at 0 0 90)
			(layer "B.Fab")
			(effects
				(font
					(size 1.27 1.27)
				)
				(justify mirror)
			)
		)
		(duplicate_pad_numbers_are_jumpers no)
		(pad "121" smd rect
			(at 0 107.100116 270)
			(size 1.8034 0.508)
			(layers "B.Cu" "B.Mask" "B.Paste")
			(net "M_K_DQS_DP<15>")
		)
		(pad "122" smd rect
			(at 0 107.95 270)
			(size 1.8034 0.508)
			(layers "B.Cu" "B.Mask" "B.Paste")
			(net "M_K_DQS_DN<15>")
		)
		(pad "123" smd rect
			(at 0 108.799884 270)
			(size 1.8034 0.508)
			(layers "B.Cu" "B.Mask" "B.Paste")
			(net "GND")
		)
		(pad "124" smd rect
			(at 0 109.650022 270)
			(size 1.8034 0.508)
			(layers "B.Cu" "B.Mask" "B.Paste")
			(net "M_K_DQ<54>")
		)
		(pad "125" smd rect
			(at 0 110.499906 270)
			(size 1.8034 0.508)
			(layers "B.Cu" "B.Mask" "B.Paste")
			(net "GND")
		)
		(pad "126" smd rect
			(at 0 111.350044 270)
			(size 1.8034 0.508)
			(layers "B.Cu" "B.Mask" "B.Paste")
			(net "M_K_DQ<50>")
		)
		(pad "127" smd rect
			(at 0 112.199928 270)
			(size 1.8034 0.508)
			(layers "B.Cu" "B.Mask" "B.Paste")
			(net "GND")
		)
		(pad "128" smd rect
			(at 0 113.050066 270)
			(size 1.8034 0.508)
			(layers "B.Cu" "B.Mask" "B.Paste")
			(net "M_K_DQ<60>")
		)
		(pad "129" smd rect
			(at 0 113.89995 270)
			(size 1.8034 0.508)
			(layers "B.Cu" "B.Mask" "B.Paste")
			(net "GND")
		)
		(pad "130" smd rect
			(at 0 114.750088 270)
			(size 1.8034 0.508)
			(layers "B.Cu" "B.Mask" "B.Paste")
			(net "M_K_DQ<56>")
		)
		(pad "131" smd rect
			(at 0 115.599972 270)
			(size 1.8034 0.508)
			(layers "B.Cu" "B.Mask" "B.Paste")
			(net "GND")
		)
		(pad "132" smd rect
			(at 0 116.45011 270)
			(size 1.8034 0.508)
			(layers "B.Cu" "B.Mask" "B.Paste")
			(net "M_K_DQS_DP<16>")
		)
		(pad "133" smd rect
			(at 0 117.299994 270)
			(size 1.8034 0.508)
			(layers "B.Cu" "B.Mask" "B.Paste")
			(net "M_K_DQS_DN<16>")
		)
		(pad "134" smd rect
			(at 0 118.149878 270)
			(size 1.8034 0.508)
			(layers "B.Cu" "B.Mask" "B.Paste")
			(net "GND")
		)
		(pad "135" smd rect
			(at 0 119.000016 270)
			(size 1.8034 0.508)
			(layers "B.Cu" "B.Mask" "B.Paste")
			(net "M_K_DQ<62>")
		)
		(pad "136" smd rect
			(at 0 119.8499 270)
			(size 1.8034 0.508)
			(layers "B.Cu" "B.Mask" "B.Paste")
			(net "GND")
		)
		(pad "137" smd rect
			(at 0 120.700038 270)
			(size 1.8034 0.508)
			(layers "B.Cu" "B.Mask" "B.Paste")
			(net "M_K_DQ<58>")
		)
		(pad "138" smd rect
			(at 0 121.549922 270)
			(size 1.8034 0.508)
			(layers "B.Cu" "B.Mask" "B.Paste")
			(net "GND")
		)
		(pad "139" smd rect
			(at 0 122.40006 270)
			(size 1.8034 0.508)
			(layers "B.Cu" "B.Mask" "B.Paste")
			(net "PVPP_KLM")
		)
		(pad "140" smd rect
			(at 0 123.249944 270)
			(size 1.8034 0.508)
			(layers "B.Cu" "B.Mask" "B.Paste")
			(net "GND")
		)
		(pad "141" smd rect
			(at 0 124.100082 270)
			(size 1.8034 0.508)
			(layers "B.Cu" "B.Mask" "B.Paste")
			(net "SMB_DDR_KLM_VPP_SCL")
		)
		(pad "142" smd rect
			(at 0 124.949966 270)
			(size 1.8034 0.508)
			(layers "B.Cu" "B.Mask" "B.Paste")
			(net "PVPP_KLM")
		)
		(pad "143" smd rect
			(at 0 125.800104 270)
			(size 1.8034 0.508)
			(layers "B.Cu" "B.Mask" "B.Paste")
			(net "PVPP_KLM")
		)
		(pad "144" smd rect
			(at 0 126.649988 270)
			(size 1.8034 0.508)
			(layers "B.Cu" "B.Mask" "B.Paste")
			(net "TP_CH_K_DIMM0_RFU_2")
		)
		(pad "145" smd rect
			(at -4.59994 0 270)
			(size 1.8034 0.508)
			(layers "B.Cu" "B.Mask" "B.Paste")
			(net "P12V_NVDIMM_KLM")
		)
		(pad "146" smd rect
			(at -4.59994 0.849884 270)
			(size 1.8034 0.508)
			(layers "B.Cu" "B.Mask" "B.Paste")
			(net "M_K_VREF")
		)
		(pad "147" smd rect
			(at -4.59994 1.700022 270)
			(size 1.8034 0.508)
			(layers "B.Cu" "B.Mask" "B.Paste")
			(net "GND")
		)
		(pad "148" smd rect
			(at -4.59994 2.549906 270)
			(size 1.8034 0.508)
			(layers "B.Cu" "B.Mask" "B.Paste")
			(net "M_K_DQ<5>")
		)
		(pad "149" smd rect
			(at -4.59994 3.400044 270)
			(size 1.8034 0.508)
			(layers "B.Cu" "B.Mask" "B.Paste")
			(net "GND")
		)
		(pad "150" smd rect
			(at -4.59994 4.249928 270)
			(size 1.8034 0.508)
			(layers "B.Cu" "B.Mask" "B.Paste")
			(net "M_K_DQ<1>")
		)
		(pad "151" smd rect
			(at -4.59994 5.100066 270)
			(size 1.8034 0.508)
			(layers "B.Cu" "B.Mask" "B.Paste")
			(net "GND")
		)
		(pad "152" smd rect
			(at -4.59994 5.94995 270)
			(size 1.8034 0.508)
			(layers "B.Cu" "B.Mask" "B.Paste")
			(net "M_K_DQS_DN<0>")
		)
		(pad "153" smd rect
			(at -4.59994 6.800088 270)
			(size 1.8034 0.508)
			(layers "B.Cu" "B.Mask" "B.Paste")
			(net "M_K_DQS_DP<0>")
		)
		(pad "154" smd rect
			(at -4.59994 7.649972 270)
			(size 1.8034 0.508)
			(layers "B.Cu" "B.Mask" "B.Paste")
			(net "GND")
		)
		(pad "155" smd rect
			(at -4.59994 8.50011 270)
			(size 1.8034 0.508)
			(layers "B.Cu" "B.Mask" "B.Paste")
			(net "M_K_DQ<7>")
		)
		(pad "156" smd rect
			(at -4.59994 9.349994 270)
			(size 1.8034 0.508)
			(layers "B.Cu" "B.Mask" "B.Paste")
			(net "GND")
		)
		(pad "157" smd rect
			(at -4.59994 10.199878 270)
			(size 1.8034 0.508)
			(layers "B.Cu" "B.Mask" "B.Paste")
			(net "M_K_DQ<3>")
		)
		(pad "158" smd rect
			(at -4.59994 11.050016 270)
			(size 1.8034 0.508)
			(layers "B.Cu" "B.Mask" "B.Paste")
			(net "GND")
		)
		(pad "159" smd rect
			(at -4.59994 11.8999 270)
			(size 1.8034 0.508)
			(layers "B.Cu" "B.Mask" "B.Paste")
			(net "M_K_DQ<13>")
		)
		(pad "160" smd rect
			(at -4.59994 12.750038 270)
			(size 1.8034 0.508)
			(layers "B.Cu" "B.Mask" "B.Paste")
			(net "GND")
		)
		(pad "161" smd rect
			(at -4.59994 13.599922 270)
			(size 1.8034 0.508)
			(layers "B.Cu" "B.Mask" "B.Paste")
			(net "M_K_DQ<9>")
		)
		(pad "162" smd rect
			(at -4.59994 14.45006 270)
			(size 1.8034 0.508)
			(layers "B.Cu" "B.Mask" "B.Paste")
			(net "GND")
		)
		(pad "163" smd rect
			(at -4.59994 15.299944 270)
			(size 1.8034 0.508)
			(layers "B.Cu" "B.Mask" "B.Paste")
			(net "M_K_DQS_DN<1>")
		)
		(pad "164" smd rect
			(at -4.59994 16.150082 270)
			(size 1.8034 0.508)
			(layers "B.Cu" "B.Mask" "B.Paste")
			(net "M_K_DQS_DP<1>")
		)
		(pad "165" smd rect
			(at -4.59994 16.999966 270)
			(size 1.8034 0.508)
			(layers "B.Cu" "B.Mask" "B.Paste")
			(net "GND")
		)
		(pad "166" smd rect
			(at -4.59994 17.850104 270)
			(size 1.8034 0.508)
			(layers "B.Cu" "B.Mask" "B.Paste")
			(net "M_K_DQ<15>")
		)
		(pad "167" smd rect
			(at -4.59994 18.699988 270)
			(size 1.8034 0.508)
			(layers "B.Cu" "B.Mask" "B.Paste")
			(net "GND")
		)
		(pad "168" smd rect
			(at -4.59994 19.550126 270)
			(size 1.8034 0.508)
			(layers "B.Cu" "B.Mask" "B.Paste")
			(net "M_K_DQ<11>")
		)
		(pad "169" smd rect
			(at -4.59994 20.40001 270)
			(size 1.8034 0.508)
			(layers "B.Cu" "B.Mask" "B.Paste")
			(net "GND")
		)
		(pad "170" smd rect
			(at -4.59994 21.249894 270)
			(size 1.8034 0.508)
			(layers "B.Cu" "B.Mask" "B.Paste")
			(net "M_K_DQ<21>")
		)
		(pad "171" smd rect
			(at -4.59994 22.100032 270)
			(size 1.8034 0.508)
			(layers "B.Cu" "B.Mask" "B.Paste")
			(net "GND")
		)
		(pad "172" smd rect
			(at -4.59994 22.949916 270)
			(size 1.8034 0.508)
			(layers "B.Cu" "B.Mask" "B.Paste")
			(net "M_K_DQ<17>")
		)
		(pad "173" smd rect
			(at -4.59994 23.800054 270)
			(size 1.8034 0.508)
			(layers "B.Cu" "B.Mask" "B.Paste")
			(net "GND")
		)
		(pad "174" smd rect
			(at -4.59994 24.649938 270)
			(size 1.8034 0.508)
			(layers "B.Cu" "B.Mask" "B.Paste")
			(net "M_K_DQS_DN<2>")
		)
		(pad "175" smd rect
			(at -4.59994 25.500076 270)
			(size 1.8034 0.508)
			(layers "B.Cu" "B.Mask" "B.Paste")
			(net "M_K_DQS_DP<2>")
		)
		(pad "176" smd rect
			(at -4.59994 26.34996 270)
			(size 1.8034 0.508)
			(layers "B.Cu" "B.Mask" "B.Paste")
			(net "GND")
		)
		(pad "177" smd rect
			(at -4.59994 27.200098 270)
			(size 1.8034 0.508)
			(layers "B.Cu" "B.Mask" "B.Paste")
			(net "M_K_DQ<23>")
		)
		(pad "178" smd rect
			(at -4.59994 28.049982 270)
			(size 1.8034 0.508)
			(layers "B.Cu" "B.Mask" "B.Paste")
			(net "GND")
		)
		(pad "179" smd rect
			(at -4.59994 28.90012 270)
			(size 1.8034 0.508)
			(layers "B.Cu" "B.Mask" "B.Paste")
			(net "M_K_DQ<19>")
		)
		(pad "180" smd rect
			(at -4.59994 29.750004 270)
			(size 1.8034 0.508)
			(layers "B.Cu" "B.Mask" "B.Paste")
			(net "GND")
		)
		(pad "181" smd rect
			(at -4.59994 30.599888 270)
			(size 1.8034 0.508)
			(layers "B.Cu" "B.Mask" "B.Paste")
			(net "M_K_DQ<29>")
		)
		(pad "182" smd rect
			(at -4.59994 31.450026 270)
			(size 1.8034 0.508)
			(layers "B.Cu" "B.Mask" "B.Paste")
			(net "GND")
		)
		(pad "183" smd rect
			(at -4.59994 32.29991 270)
			(size 1.8034 0.508)
			(layers "B.Cu" "B.Mask" "B.Paste")
			(net "M_K_DQ<25>")
		)
		(pad "184" smd rect
			(at -4.59994 33.150048 270)
			(size 1.8034 0.508)
			(layers "B.Cu" "B.Mask" "B.Paste")
			(net "GND")
		)
		(pad "185" smd rect
			(at -4.59994 33.999932 270)
			(size 1.8034 0.508)
			(layers "B.Cu" "B.Mask" "B.Paste")
			(net "M_K_DQS_DN<3>")
		)
		(pad "186" smd rect
			(at -4.59994 34.85007 270)
			(size 1.8034 0.508)
			(layers "B.Cu" "B.Mask" "B.Paste")
			(net "M_K_DQS_DP<3>")
		)
		(pad "187" smd rect
			(at -4.59994 35.699954 270)
			(size 1.8034 0.508)
			(layers "B.Cu" "B.Mask" "B.Paste")
			(net "GND")
		)
		(pad "188" smd rect
			(at -4.59994 36.550092 270)
			(size 1.8034 0.508)
			(layers "B.Cu" "B.Mask" "B.Paste")
			(net "M_K_DQ<31>")
		)
		(pad "189" smd rect
			(at -4.59994 37.399976 270)
			(size 1.8034 0.508)
			(layers "B.Cu" "B.Mask" "B.Paste")
			(net "GND")
		)
		(pad "190" smd rect
			(at -4.59994 38.250114 270)
			(size 1.8034 0.508)
			(layers "B.Cu" "B.Mask" "B.Paste")
			(net "M_K_DQ<27>")
		)
		(pad "191" smd rect
			(at -4.59994 39.099998 270)
			(size 1.8034 0.508)
			(layers "B.Cu" "B.Mask" "B.Paste")
			(net "GND")
		)
		(pad "192" smd rect
			(at -4.59994 39.949882 270)
			(size 1.8034 0.508)
			(layers "B.Cu" "B.Mask" "B.Paste")
			(net "M_K_ECC<5>")
		)
		(pad "193" smd rect
			(at -4.59994 40.80002 270)
			(size 1.8034 0.508)
			(layers "B.Cu" "B.Mask" "B.Paste")
			(net "GND")
		)
		(pad "194" smd rect
			(at -4.59994 41.649904 270)
			(size 1.8034 0.508)
			(layers "B.Cu" "B.Mask" "B.Paste")
			(net "M_K_ECC<1>")
		)
		(pad "195" smd rect
			(at -4.59994 42.500042 270)
			(size 1.8034 0.508)
			(layers "B.Cu" "B.Mask" "B.Paste")
			(net "GND")
		)
		(pad "196" smd rect
			(at -4.59994 43.349926 270)
			(size 1.8034 0.508)
			(layers "B.Cu" "B.Mask" "B.Paste")
			(net "M_K_DQS_DN<8>")
		)
		(pad "197" smd rect
			(at -4.59994 44.200064 270)
			(size 1.8034 0.508)
			(layers "B.Cu" "B.Mask" "B.Paste")
			(net "M_K_DQS_DP<8>")
		)
		(pad "198" smd rect
			(at -4.59994 45.049948 270)
			(size 1.8034 0.508)
			(layers "B.Cu" "B.Mask" "B.Paste")
			(net "GND")
		)
		(pad "199" smd rect
			(at -4.59994 45.900086 270)
			(size 1.8034 0.508)
			(layers "B.Cu" "B.Mask" "B.Paste")
			(net "M_K_ECC<7>")
		)
		(pad "200" smd rect
			(at -4.59994 46.74997 270)
			(size 1.8034 0.508)
			(layers "B.Cu" "B.Mask" "B.Paste")
			(net "GND")
		)
		(pad "201" smd rect
			(at -4.59994 47.600108 270)
			(size 1.8034 0.508)
			(layers "B.Cu" "B.Mask" "B.Paste")
			(net "M_K_ECC<3>")
		)
		(pad "202" smd rect
			(at -4.59994 48.449992 270)
			(size 1.8034 0.508)
			(layers "B.Cu" "B.Mask" "B.Paste")
			(net "GND")
		)
		(pad "203" smd rect
			(at -4.59994 49.299876 270)
			(size 1.8034 0.508)
			(layers "B.Cu" "B.Mask" "B.Paste")
			(net "M_K_CKE<3>")
		)
		(pad "204" smd rect
			(at -4.59994 50.150014 270)
			(size 1.8034 0.508)
			(layers "B.Cu" "B.Mask" "B.Paste")
			(net "PVDDQ_KLM")
		)
		(pad "205" smd rect
			(at -4.59994 50.999898 270)
			(size 1.8034 0.508)
			(layers "B.Cu" "B.Mask" "B.Paste")
			(net "TP_CH_K_DIMM0_RFU_0")
		)
		(pad "206" smd rect
			(at -4.59994 51.850036 270)
			(size 1.8034 0.508)
			(layers "B.Cu" "B.Mask" "B.Paste")
			(net "PVDDQ_KLM")
		)
		(pad "207" smd rect
			(at -4.59994 52.69992 270)
			(size 1.8034 0.508)
			(layers "B.Cu" "B.Mask" "B.Paste")
			(net "M_K_BG<1>")
		)
		(pad "208" smd rect
			(at -4.59994 53.550058 270)
			(size 1.8034 0.508)
			(layers "B.Cu" "B.Mask" "B.Paste")
			(net "M_K_ALERT_N")
		)
		(pad "209" smd rect
			(at -4.59994 54.399942 270)
			(size 1.8034 0.508)
			(layers "B.Cu" "B.Mask" "B.Paste")
			(net "PVDDQ_KLM")
		)
		(pad "210" smd rect
			(at -4.59994 55.25008 270)
			(size 1.8034 0.508)
			(layers "B.Cu" "B.Mask" "B.Paste")
			(net "M_K_MA<11>")
		)
		(pad "211" smd rect
			(at -4.59994 56.099964 270)
			(size 1.8034 0.508)
			(layers "B.Cu" "B.Mask" "B.Paste")
			(net "M_K_MA<7>")
		)
		(pad "212" smd rect
			(at -4.59994 56.950102 270)
			(size 1.8034 0.508)
			(layers "B.Cu" "B.Mask" "B.Paste")
			(net "PVDDQ_KLM")
		)
		(pad "213" smd rect
			(at -4.59994 57.799986 270)
			(size 1.8034 0.508)
			(layers "B.Cu" "B.Mask" "B.Paste")
			(net "M_K_MA<5>")
		)
		(pad "214" smd rect
			(at -4.59994 58.650124 270)
			(size 1.8034 0.508)
			(layers "B.Cu" "B.Mask" "B.Paste")
			(net "M_K_MA<4>")
		)
		(pad "215" smd rect
			(at -4.59994 59.500008 270)
			(size 1.8034 0.508)
			(layers "B.Cu" "B.Mask" "B.Paste")
			(net "PVDDQ_KLM")
		)
		(pad "216" smd rect
			(at -4.59994 60.349892 270)
			(size 1.8034 0.508)
			(layers "B.Cu" "B.Mask" "B.Paste")
			(net "M_K_MA<2>")
		)
		(pad "217" smd rect
			(at -4.59994 61.20003 270)
			(size 1.8034 0.508)
			(layers "B.Cu" "B.Mask" "B.Paste")
			(net "PVDDQ_KLM")
		)
		(pad "218" smd rect
			(at -4.59994 62.049914 270)
			(size 1.8034 0.508)
			(layers "B.Cu" "B.Mask" "B.Paste")
			(net "M_K_CLK_DP<3>")
		)
		(pad "219" smd rect
			(at -4.59994 62.900052 270)
			(size 1.8034 0.508)
			(layers "B.Cu" "B.Mask" "B.Paste")
			(net "M_K_CLK_DN<3>")
		)
		(pad "220" smd rect
			(at -4.59994 63.749936 270)
			(size 1.8034 0.508)
			(layers "B.Cu" "B.Mask" "B.Paste")
			(net "PVDDQ_KLM")
		)
		(pad "221" smd rect
			(at -4.59994 64.600074 270)
			(size 1.8034 0.508)
			(layers "B.Cu" "B.Mask" "B.Paste")
			(net "PVTT_KLM")
		)
		(pad "222" smd rect
			(at -4.59994 70.550024 270)
			(size 1.8034 0.508)
			(layers "B.Cu" "B.Mask" "B.Paste")
			(net "M_K_PAR")
		)
		(pad "223" smd rect
			(at -4.59994 71.399908 270)
			(size 1.8034 0.508)
			(layers "B.Cu" "B.Mask" "B.Paste")
			(net "PVDDQ_KLM")
		)
		(pad "224" smd rect
			(at -4.59994 72.250046 270)
			(size 1.8034 0.508)
			(layers "B.Cu" "B.Mask" "B.Paste")
			(net "M_K_BA<1>")
		)
		(pad "225" smd rect
			(at -4.59994 73.09993 270)
			(size 1.8034 0.508)
			(layers "B.Cu" "B.Mask" "B.Paste")
			(net "M_K_MA<10>")
		)
		(pad "226" smd rect
			(at -4.59994 73.950068 270)
			(size 1.8034 0.508)
			(layers "B.Cu" "B.Mask" "B.Paste")
			(net "PVDDQ_KLM")
		)
		(pad "227" smd rect
			(at -4.59994 74.799952 270)
			(size 1.8034 0.508)
			(layers "B.Cu" "B.Mask" "B.Paste")
			(net "TP_CH_K_DIMM0_RFU_1")
		)
		(pad "228" smd rect
			(at -4.59994 75.65009 270)
			(size 1.8034 0.508)
			(layers "B.Cu" "B.Mask" "B.Paste")
			(net "M_K_MA<14>")
		)
		(pad "229" smd rect
			(at -4.59994 76.499974 270)
			(size 1.8034 0.508)
			(layers "B.Cu" "B.Mask" "B.Paste")
			(net "PVDDQ_KLM")
		)
		(pad "230" smd rect
			(at -4.59994 77.350112 270)
			(size 1.8034 0.508)
			(layers "B.Cu" "B.Mask" "B.Paste")
			(net "FM_ADR_COMPLETE_KLM_N")
		)
		(pad "231" smd rect
			(at -4.59994 78.199996 270)
			(size 1.8034 0.508)
			(layers "B.Cu" "B.Mask" "B.Paste")
			(net "PVDDQ_KLM")
		)
		(pad "232" smd rect
			(at -4.59994 79.04988 270)
			(size 1.8034 0.508)
			(layers "B.Cu" "B.Mask" "B.Paste")
			(net "M_K_MA<13>")
		)
		(pad "233" smd rect
			(at -4.59994 79.900018 270)
			(size 1.8034 0.508)
			(layers "B.Cu" "B.Mask" "B.Paste")
			(net "PVDDQ_KLM")
		)
		(pad "234" smd rect
			(at -4.59994 80.749902 270)
			(size 1.8034 0.508)
			(layers "B.Cu" "B.Mask" "B.Paste")
			(net "M_K_MA<17>")
		)
		(pad "235" smd rect
			(at -4.59994 81.60004 270)
			(size 1.8034 0.508)
			(layers "B.Cu" "B.Mask" "B.Paste")
			(net "M_K_C<2>")
		)
		(pad "236" smd rect
			(at -4.59994 82.449924 270)
			(size 1.8034 0.508)
			(layers "B.Cu" "B.Mask" "B.Paste")
			(net "PVDDQ_KLM")
		)
		(pad "237" smd rect
			(at -4.59994 83.300062 270)
			(size 1.8034 0.508)
			(layers "B.Cu" "B.Mask" "B.Paste")
			(net "M_K_CS_N<7>")
		)
		(pad "238" smd rect
			(at -4.59994 84.149946 270)
			(size 1.8034 0.508)
			(layers "B.Cu" "B.Mask" "B.Paste")
			(net "GND")
		)
		(pad "239" smd rect
			(at -4.59994 85.000084 270)
			(size 1.8034 0.508)
			(layers "B.Cu" "B.Mask" "B.Paste")
			(net "GND")
		)
		(pad "240" smd rect
			(at -4.59994 85.849968 270)
			(size 1.8034 0.508)
			(layers "B.Cu" "B.Mask" "B.Paste")
			(net "M_K_DQ<37>")
		)
	)
)
